# TIMECARD (Time Appliance Project (Time Card)) — schematic netlist excerpt (pin names and nets, part order shuffled) for the footprints in the layout excerpt that follows; sources: Cadence DE-HDL packaged netlist, KiCad conversion of R4006-B0001-02_R01.brd

R209  RESISTOR  4.7KOHM 1%  pkg SMC_0402R_H016  page 10 : \1\ = FPGA_CFG_INIT_N ; \2\ = XP3R3V_FPGA
R174  RESISTOR  10KOHM 1%  pkg SMC_0402R_H016  page 30 : \1\ = XP1R8V_EN_R ; \2\ = SG

(kicad_pcb
	(version 20260206)
	(generator "pcbnew")
	(generator_version "10.0")
	(general
		(thickness 1.6)
		(legacy_teardrops no)
	)
	(paper "A4")
	(title_block
		(title "timecard-production-celestica-r4006 — R4006-B0001-02_R01.brd")
		(comment 1 "Time Appliance Project (Time Card) / footprints 787-788 of 1113")
	)
	(layers
		(0 "F.Cu" signal "TOP")
		(4 "In1.Cu" signal "L02_GND1")
		(6 "In2.Cu" signal "L03_SIG1")
		(8 "In3.Cu" signal "L04_GND2")
		(10 "In4.Cu" signal "L05_VCC1")
		(12 "In5.Cu" signal "L06_VCC2")
		(14 "In6.Cu" signal "L07_GND3")
		(16 "In7.Cu" signal "L08_SIG2")
		(18 "In8.Cu" signal "L09_GND4")
		(2 "B.Cu" signal "BOTTOM")
		(9 "F.Adhes" user "F.Adhesive")
		(11 "B.Adhes" user "B.Adhesive")
		(13 "F.Paste" user "Package Geometry/Pastemask Top")
		(15 "B.Paste" user "Package Geometry/Pastemask Bottom")
		(5 "F.SilkS" user "Ref Des/Silkscreen Top")
		(7 "B.SilkS" user "Ref Des/Silkscreen Bottom")
		(1 "F.Mask" user "Board Geometry/Soldermask Top")
		(3 "B.Mask" user "Board Geometry/Soldermask Bottom")
		(17 "Dwgs.User" user "User.Drawings")
		(19 "Cmts.User" user "User.Comments")
		(21 "Eco1.User" user "User.Eco1")
		(23 "Eco2.User" user "User.Eco2")
		(25 "Edge.Cuts" user "Board Geometry/Outline")
		(27 "Margin" user)
		(31 "F.CrtYd" user "Package Geometry/Place Bound Top")
		(29 "B.CrtYd" user "Package Geometry/Place Bound Bottom")
		(35 "F.Fab" user "Ref Des/Assembly Top")
		(33 "B.Fab" user "Ref Des/Assembly Bottom")
	)
	(footprint ""
		(layer "B.Cu")
		(at 126.0094 -68.7578 -90)
		(property "Reference" "R174"
			(at 1.7018 1.33477 270)
			(unlocked yes)
			(layer "B.SilkS")
			(effects
				(font
					(size 0.7874 0.5842)
					(thickness 0.1524)
				)
				(justify mirror)
			)
		)
		(property "Value" "VAL*"
			(at -0.02032 2.13233 270)
			(unlocked yes)
			(layer "B.Fab")
			(hide yes)
			(effects
				(font
					(size 0.7874 0.5842)
					(thickness 0.1524)
				)
				(justify mirror)
			)
		)
		(property "Tolerance" "TOL*"
			(at -0.044704 3.05435 270)
			(unlocked yes)
			(layer "Cmts.User")
			(hide yes)
			(effects
				(font
					(size 0.7874 0.5842)
					(thickness 0.1524)
				)
				(justify mirror)
			)
		)
		(property "User Part Number" "PARTNUM*"
			(at -0.02032 4.024884 270)
			(unlocked yes)
			(layer "Cmts.User")
			(hide yes)
			(effects
				(font
					(size 0.7874 0.5842)
					(thickness 0.1524)
				)
				(justify mirror)
			)
		)
		(property "Device Type" "RESISTOR-G155-11002-01,10KOHM,A"
			(at -0.008382 1.210564 270)
			(unlocked yes)
			(layer "B.Fab")
			(hide yes)
			(effects
				(font
					(size 0.7874 0.5842)
					(thickness 0.1524)
				)
				(justify mirror)
			)
		)
		(duplicate_pad_numbers_are_jumpers no)
		(fp_line
			(start -1.143 0.5588)
			(end -1.143 -0.5588)
			(stroke
				(width 0.1)
				(type default)
			)
			(layer "B.SilkS")
		)
		(fp_line
			(start 1.143 0.5588)
			(end -1.143 0.5588)
			(stroke
				(width 0.1)
				(type default)
			)
			(layer "B.SilkS")
		)
		(fp_line
			(start -1.143 -0.5588)
			(end 1.143 -0.5588)
			(stroke
				(width 0.1)
				(type default)
			)
			(layer "B.SilkS")
		)
		(fp_line
			(start 1.143 -0.5588)
			(end 1.143 0.5588)
			(stroke
				(width 0.1)
				(type default)
			)
			(layer "B.SilkS")
		)
		(fp_rect
			(start -1.143 -0.5588)
			(end 1.143 0.5588)
			(stroke
				(width 0)
				(type default)
			)
			(fill no)
			(layer "B.CrtYd")
		)
		(fp_line
			(start -0.508 0.3048)
			(end -0.508 -0.3048)
			(stroke
				(width 0.1)
				(type default)
			)
			(layer "B.Fab")
		)
		(fp_line
			(start 0.508 0.3048)
			(end -0.508 0.3048)
			(stroke
				(width 0.1)
				(type default)
			)
			(layer "B.Fab")
		)
		(fp_line
			(start -0.508 -0.3048)
			(end 0.508 -0.3048)
			(stroke
				(width 0.1)
				(type default)
			)
			(layer "B.Fab")
		)
		(fp_line
			(start 0.508 -0.3048)
			(end 0.508 0.3048)
			(stroke
				(width 0.1)
				(type default)
			)
			(layer "B.Fab")
		)
		(pad "1" smd rect
			(at 0.5334 0 90)
			(size 0.7112 0.6096)
			(layers "B.Cu" "B.Mask" "B.Paste")
			(net "XP1R8V_EN_R")
		)
		(pad "2" smd rect
			(at -0.5334 0 90)
			(size 0.7112 0.6096)
			(layers "B.Cu" "B.Mask" "B.Paste")
			(net "SG")
		)
		(zone
			(layer "B.Cu")
			(hatch none 0.5)
			(connect_pads
				(clearance 0)
			)
			(min_thickness 0.25)
			(keepout
				(tracks allowed)
				(vias not_allowed)
				(pads allowed)
				(copperpour not_allowed)
				(footprints allowed)
			)
			(placement
				(enabled no)
				(sheetname "")
			)
			(fill
				(thermal_gap 0.5)
				(thermal_bridge_width 0.5)
				(island_removal_mode 0)
			)
			(polygon
				(pts
					(xy 126.3142 -68.834) (xy 125.7046 -68.834) (xy 125.7046 -68.6816) (xy 126.3142 -68.6816)
				)
			)
		)
	)
	(footprint ""
		(layer "B.Cu")
		(at 124.587 -44.831 180)
		(property "Reference" "R209"
			(at -3.683 -0.16637 0)
			(unlocked yes)
			(layer "B.SilkS")
			(effects
				(font
					(size 0.7874 0.5842)
					(thickness 0.1524)
				)
				(justify mirror)
			)
		)
		(property "Value" "VAL*"
			(at -0.02032 2.13233 180)
			(unlocked yes)
			(layer "B.Fab")
			(hide yes)
			(effects
				(font
					(size 0.7874 0.5842)
					(thickness 0.1524)
				)
				(justify mirror)
			)
		)
		(property "Device Type" "RESISTOR-G155-14701-01,4.7KOHMA"
			(at -0.008382 1.210564 180)
			(unlocked yes)
			(layer "B.Fab")
			(hide yes)
			(effects
				(font
					(size 0.7874 0.5842)
					(thickness 0.1524)
				)
				(justify mirror)
			)
		)
		(property "User Part Number" "PARTNUM*"
			(at -0.02032 4.024884 180)
			(unlocked yes)
			(layer "Cmts.User")
			(hide yes)
			(effects
				(font
					(size 0.7874 0.5842)
					(thickness 0.1524)
				)
				(justify mirror)
			)
		)
		(property "Tolerance" "TOL*"
			(at -0.044704 3.05435 180)
			(unlocked yes)
			(layer "Cmts.User")
			(hide yes)
			(effects
				(font
					(size 0.7874 0.5842)
					(thickness 0.1524)
				)
				(justify mirror)
			)
		)
		(duplicate_pad_numbers_are_jumpers no)
		(fp_line
			(start 1.143 0.5588)
			(end -1.143 0.5588)
			(stroke
				(width 0.1)
				(type default)
			)
			(layer "B.SilkS")
		)
		(fp_line
			(start 1.143 -0.5588)
			(end 1.143 0.5588)
			(stroke
				(width 0.1)
				(type default)
			)
			(layer "B.SilkS")
		)
		(fp_line
			(start -1.143 0.5588)
			(end -1.143 -0.5588)
			(stroke
				(width 0.1)
				(type default)
			)
			(layer "B.SilkS")
		)
		(fp_line
			(start -1.143 -0.5588)
			(end 1.143 -0.5588)
			(stroke
				(width 0.1)
				(type default)
			)
			(layer "B.SilkS")
		)
		(fp_rect
			(start -1.143 0.5588)
			(end 1.143 -0.5588)
			(stroke
				(width 0)
				(type default)
			)
			(fill no)
			(layer "B.CrtYd")
		)
		(fp_line
			(start 0.508 0.3048)
			(end -0.508 0.3048)
			(stroke
				(width 0.1)
				(type default)
			)
			(layer "B.Fab")
		)
		(fp_line
			(start 0.508 -0.3048)
			(end 0.508 0.3048)
			(stroke
				(width 0.1)
				(type default)
			)
			(layer "B.Fab")
		)
		(fp_line
			(start -0.508 0.3048)
			(end -0.508 -0.3048)
			(stroke
				(width 0.1)
				(type default)
			)
			(layer "B.Fab")
		)
		(fp_line
			(start -0.508 -0.3048)
			(end 0.508 -0.3048)
			(stroke
				(width 0.1)
				(type default)
			)
			(layer "B.Fab")
		)
		(pad "1" smd rect
			(at 0.5334 0)
			(size 0.7112 0.6096)
			(layers "B.Cu" "B.Mask" "B.Paste")
			(net "FPGA_CFG_INIT_N")
		)
		(pad "2" smd rect
			(at -0.5334 0)
			(size 0.7112 0.6096)
			(layers "B.Cu" "B.Mask" "B.Paste")
			(net "XP3R3V_FPGA")
		)
		(zone
			(layer "B.Cu")
			(hatch none 0.5)
			(connect_pads
				(clearance 0)
			)
			(min_thickness 0.25)
			(keepout
				(tracks allowed)
				(vias not_allowed)
				(pads allowed)
				(copperpour not_allowed)
				(footprints allowed)
			)
			(placement
				(enabled no)
				(sheetname "")
			)
			(fill
				(thermal_gap 0.5)
				(thermal_bridge_width 0.5)
				(island_removal_mode 0)
			)
			(polygon
				(pts
					(xy 124.6632 -45.1358) (xy 124.5108 -45.1358) (xy 124.5108 -44.5262) (xy 124.6632 -44.5262)
				)
			)
		)
	)
)
